FILE_TYPE = MULTI_PHYS_TABLE;

PART 'SCHOTTKY_DUAL_12A_3C'

{========================================================================================}
:VALUE         | PART_TYPE | MATERIAL | PART_NUMBER    = STANDARD        | LIFECYCLE      | PART_NUMBER   | JEDEC_TYPE    | DESCRIPTION                                | MANUFTR | MANUF_PN      | RD_CMPLS_LVL | CMPLS_LVL | CLASS | DIP_SMD | FP_ECN | FROM_PJ      | DATA                      | EE_CHECK_LIST | STATUS | PSL | PREFERENCE | CREATOR | CREATEDAY  | ESD_CDM | ESD_HBM | ESD_MM | MSD  | PIN_LENGTH_LONG_PIN | PIN_LENGTH_SHORT_PIN ;
{========================================================================================}
 'SBA0540CA'   | 'SMLF'    | 'IC'     | 'BC000540Z14'(!) = ''              | ''               | 'BC000540Z14' |'SOT23_123XB'| 'DIODE SCHOTTKY SMD SBA0540CA (40V,0.5A)'  | 'PJT'   | 'SBA0540CA'   | 'EP(V1)'     | ''        | 'IC'  | ''      | ''     | 'S6V-GARY'   | 'PJT_SBA0540CA.pdf'       | ''            | ''     | ''  | ''         | ''      | '20181008' | 'NA'    | 'NA'    | 'NA'   | 'NA' | '0 MILS'            | '0 MILS'            
 'SBA0540CA'   | 'SMLF'    | 'EMPTY'  | 'BC000540Z14'(!) = ''              | ''               | 'BC000540Z14' |'SOT23_123XB'| 'DIODE SCHOTTKY SMD SBA0540CA (40V,0.5A)'  | 'PJT'   | 'SBA0540CA'   | 'EP(V1)'     | ''        | 'IC'  | ''      | ''     | 'S6V-GARY'   | 'PJT_SBA0540CA.pdf'       | ''            | ''     | ''  | ''         | ''      | '20181008' | 'NA'    | 'NA'    | 'NA'   | 'NA' | '0 MILS'            | '0 MILS'            
 'BAT54CW-7-F' | 'SMLF'    | 'IC'     | 'BCBAT54CZ01'(!) = ''               | ''               | 'BCBAT54CZ01' |'SOT323XA'| 'DIODE SMD BAT54CW-7-F(30V 0.2A SCHOTTKY)' | 'DDS'   | 'BAT54CW-7-F' | 'EP(V1)'     | 'EP(V1)'  | 'IC'  | ''      | ''     | 'L02B-SUNNY' | 'DDS_BAT54W-AW-CW-SW.pdf' | ''            | ''     | ''  | ''         | ''      | '20140331' | ''      | ''      | ''     | ''   | ''                  | ''                  
 'BAT54CW-7-F' | 'SMLF'    | 'EMPTY'  | 'BCBAT54CZ01'(!) = ''               | ''               | 'BCBAT54CZ01' |'SOT323XA'| 'DIODE SMD BAT54CW-7-F(30V 0.2A SCHOTTKY)' | 'DDS'   | 'BAT54CW-7-F' | 'EP(V1)'     | 'EP(V1)'  | 'IC'  | ''      | ''     | 'L02B-SUNNY' | 'DDS_BAT54W-AW-CW-SW.pdf' | ''            | ''     | ''  | ''         | ''      | '20140331' | ''      | ''      | ''     | ''   | ''                  | ''                  
 'BAT54CW'     | 'SMLF'    | 'IC'     | 'BCBAT54CZ13'(!) = ''              | ''               | 'BCBAT54CZ13' |'SOT323'| 'DIODE SMD BAT54CW(30V,0.2A,SOT323)'       | 'PJT'   | 'BAT54CW'     | 'EP(V1)'     | 'EP(V1)'  | 'IC'  | ''      | ''     | 'TU1H-JAMIE' | 'PJT_BAT54CW-SERIES.pdf'  | ''            | ''     | ''  | ''         | ''      | '20131016' | ''      | ''      | ''     | ''   | ''                  | ''                  
 'BAT54CW'     | 'SMLF'    | 'EMPTY'  | 'BCBAT54CZ13'(!) = ''              | ''               | 'BCBAT54CZ13' |'SOT323'| 'DIODE SMD BAT54CW(30V,0.2A,SOT323)'       | 'PJT'   | 'BAT54CW'     | 'EP(V1)'     | 'EP(V1)'  | 'IC'  | ''      | ''     | 'TU1H-JAMIE' | 'PJT_BAT54CW-SERIES.pdf'  | ''            | ''     | ''  | ''         | ''      | '20131016' | ''      | ''      | ''     | ''   | ''                  | ''                  

END_PART

END.

